FILE_TYPE = MULTI_PHYS_TABLE;

PART 'TCA9548APWR'

{========================================================================================}
:VALUE         | PART_TYPE | MATERIAL | PART_NUMBER    = STANDARD | LIFECYCLE      | PART_NUMBER   | JEDEC_TYPE  | DESCRIPTION                        | MANUFTR | MANUF_PN      | RD_CMPLS_LVL | CMPLS_LVL | FROM_PJ        | CLASS | DIP_SMD | DATA                  | EE_CHECK_LIST | FP_ECN | PSL | CREATOR | STATUS | MSD | ESD_CDM | ESD_HBM | ESD_MM | PIN_LENGTH_SHORT_PIN | PIN_LENGTH_LONG_PIN | CREATEDAY  ;
{========================================================================================}
 'TCA9548APWR' | 'SMLF'    | 'IC'     | 'AL009548K02'(!) = ''       | ''               | 'AL009548K02' |'TSSOP24XA'| 'IC OTHER(24P) TCA9548APWR(TSSOP)' | 'TIC'   | 'TCA9548APWR' | 'EP(V1)'     | 'EP(V1)'  | 'T6MB-WILLIAM' | 'IC'  | ''      | 'TIC_TCA9548APWR.pdf' | ''            | ''     | ''  | ''      | ''     | ''  | ''      | ''      | ''     | ''                   | ''                  | '20160812'
 'TCA9548APWR' | 'SMLF'    | 'EMPTY'  | 'AL009548K02'(!) = ''       | ''               | 'AL009548K02' |'TSSOP24XA'| 'IC OTHER(24P) TCA9548APWR(TSSOP)' | 'TIC'   | 'TCA9548APWR' | 'EP(V1)'     | 'EP(V1)'  | 'T6MB-WILLIAM' | 'IC'  | ''      | 'TIC_TCA9548APWR.pdf' | ''            | ''     | ''  | ''      | ''     | ''  | ''      | ''      | ''     | ''                   | ''                  | '20160812'

END_PART

END.

